(kicad_pcb
	(version 20241229)
	(generator "pcbnew")
	(generator_version "9.0")
	(general
		(thickness 1.6296)
		(legacy_teardrops no)
	)
	(paper "A3")
	(title_block
		(title "Thunderbolt to 10GbE adapter")
		(date "2026-04-21")
		(rev "1.1.0")
		(company "Antmicro Ltd")
		(comment 1 "www.antmicro.com")
		(comment 9 "footprints 635-639 of 703")
	)
	(layers
		(0 "F.Cu" signal)
		(4 "In1.Cu" signal)
		(6 "In2.Cu" signal)
		(8 "In3.Cu" signal)
		(10 "In4.Cu" signal)
		(12 "In5.Cu" signal)
		(14 "In6.Cu" signal)
		(2 "B.Cu" signal)
		(9 "F.Adhes" user "F.Adhesive")
		(11 "B.Adhes" user "B.Adhesive")
		(13 "F.Paste" user)
		(15 "B.Paste" user)
		(5 "F.SilkS" user "F.Silkscreen")
		(7 "B.SilkS" user "B.Silkscreen")
		(1 "F.Mask" user)
		(3 "B.Mask" user)
		(17 "Dwgs.User" user "User.Drawings")
		(19 "Cmts.User" user "User.Comments")
		(21 "Eco1.User" user "User.Eco1")
		(23 "Eco2.User" user "User.Eco2")
		(25 "Edge.Cuts" user)
		(27 "Margin" user)
		(31 "F.CrtYd" user "F.Courtyard")
		(29 "B.CrtYd" user "B.Courtyard")
		(35 "F.Fab" user)
		(33 "B.Fab" user)
	)
	(footprint "antmicro-footprints:R_0402_1005Metric"
		(layer "B.Cu")
		(at 135.6 127.6)
		(descr "Resistor SMD 0402")
		(tags "resistor SMD 0402")
		(property "Reference" "R58"
			(at 19.525001 -7.450001 180)
			(layer "B.SilkS")
			(effects
				(font
					(size 0.7 0.7)
					(thickness 0.15)
				)
				(justify mirror)
			)
		)
		(property "Value" "R_1M_0402"
			(at -1.011843 -1.772047 180)
			(layer "B.Fab")
			(effects
				(font
					(size 0.7 0.7)
					(thickness 0.15)
				)
				(justify left bottom mirror)
			)
		)
		(property "Datasheet" "https://www.bourns.com/docs/product-datasheets/cr.pdf"
			(at 0 0 180)
			(layer "B.Fab")
			(hide yes)
			(effects
				(font
					(size 1.27 1.27)
					(thickness 0.15)
				)
				(justify mirror)
			)
		)
		(property "Description" "SMD Chip Resistor, 1 Mohm, ± 1%, 62.5 mW, 0402 [1005 Metric], Thick Film, General Purpose"
			(at 0 0 180)
			(layer "B.Fab")
			(hide yes)
			(effects
				(font
					(size 1.27 1.27)
					(thickness 0.15)
				)
				(justify mirror)
			)
		)
		(property "MPN" "CR0402-FX-1004GLF"
			(at 0 0 0)
			(unlocked yes)
			(layer "B.Fab")
			(hide yes)
			(effects
				(font
					(size 1 1)
					(thickness 0.15)
				)
				(justify mirror)
			)
		)
		(property "Manufacturer" "Bourns"
			(at 0 0 0)
			(unlocked yes)
			(layer "B.Fab")
			(hide yes)
			(effects
				(font
					(size 1 1)
					(thickness 0.15)
				)
				(justify mirror)
			)
		)
		(property "License" "Apache-2.0"
			(at 0 0 0)
			(unlocked yes)
			(layer "B.Fab")
			(hide yes)
			(effects
				(font
					(size 1 1)
					(thickness 0.15)
				)
				(justify mirror)
			)
		)
		(property "Val" "1M"
			(at 0 0 0)
			(unlocked yes)
			(layer "B.Fab")
			(hide yes)
			(effects
				(font
					(size 1 1)
					(thickness 0.15)
				)
				(justify mirror)
			)
		)
		(property "Tolerance" "1%"
			(at 0 0 0)
			(unlocked yes)
			(layer "B.Fab")
			(hide yes)
			(effects
				(font
					(size 1 1)
					(thickness 0.15)
				)
				(justify mirror)
			)
		)
		(property "Author" "Antmicro"
			(at 0 0 0)
			(unlocked yes)
			(layer "B.Fab")
			(hide yes)
			(effects
				(font
					(size 1 1)
					(thickness 0.15)
				)
				(justify mirror)
			)
		)
		(sheetname "/TB Controller/")
		(sheetfile "tb.kicad_sch")
		(attr smd)
		(fp_rect
			(start -0.925 0.47)
			(end 0.925 -0.47)
			(stroke
				(width 0.05)
				(type default)
			)
			(fill no)
			(layer "B.CrtYd")
		)
		(fp_rect
			(start -0.5 0.25)
			(end 0.5 -0.25)
			(stroke
				(width 0.15)
				(type solid)
			)
			(fill no)
			(layer "B.Fab")
		)
		(fp_text user "License: Apache-2.0"
			(at -0.95 -5.169 180)
			(layer "B.Fab")
			(effects
				(font
					(size 0.7 0.7)
					(thickness 0.15)
				)
				(justify left bottom mirror)
			)
		)
		(fp_text user "Author: Antmicro"
			(at -0.95 -4.169 180)
			(layer "B.Fab")
			(effects
				(font
					(size 0.7 0.7)
					(thickness 0.15)
				)
				(justify left bottom mirror)
			)
		)
		(fp_text user "${REFERENCE}"
			(at -0.95 -3.168 180)
			(layer "B.Fab")
			(effects
				(font
					(size 0.7 0.7)
					(thickness 0.15)
				)
				(justify left bottom mirror)
			)
		)
		(pad "1" smd roundrect
			(at -0.48 0)
			(size 0.59 0.64)
			(layers "B.Cu" "B.Mask" "B.Paste")
			(roundrect_rratio 0.25)
			(net 231 "Net-(U4E-PB_LSTX)")
			(pintype "passive")
		)
		(pad "2" smd roundrect
			(at 0.48 0)
			(size 0.59 0.64)
			(layers "B.Cu" "B.Mask" "B.Paste")
			(roundrect_rratio 0.25)
			(net 23 "GND")
			(pintype "passive")
		)
	)
	(footprint "antmicro-footprints:SOT-323"
		(layer "B.Cu")
		(at 119.5 92.2 90)
		(property "Reference" "Q1"
			(at -5.6 0.7 270)
			(layer "B.SilkS")
			(effects
				(font
					(size 0.7 0.7)
					(thickness 0.15)
				)
				(justify left bottom mirror)
			)
		)
		(property "Value" "BC817-25W"
			(at 0 -2.749 270)
			(layer "B.Fab")
			(effects
				(font
					(size 0.7 0.7)
					(thickness 0.15)
				)
				(justify left bottom mirror)
			)
		)
		(property "Datasheet" "https://assets.nexperia.com/documents/data-sheet/BC817W_SER.pdf"
			(at 0 0 270)
			(layer "B.Fab")
			(hide yes)
			(effects
				(font
					(size 1.27 1.27)
					(thickness 0.15)
				)
				(justify mirror)
			)
		)
		(property "Description" "Bipolar (BJT) Single Transistor, NPN, 45 V, 500 mA, 200 mW, SOT-323, Surface Mount"
			(at 0 0 270)
			(layer "B.Fab")
			(hide yes)
			(effects
				(font
					(size 1.27 1.27)
					(thickness 0.15)
				)
				(justify mirror)
			)
		)
		(property "MPN" "BC817-25W,115"
			(at 0 0 90)
			(unlocked yes)
			(layer "B.Fab")
			(hide yes)
			(effects
				(font
					(size 1 1)
					(thickness 0.15)
				)
				(justify mirror)
			)
		)
		(property "Manufacturer" "Nexperia"
			(at 0 0 90)
			(unlocked yes)
			(layer "B.Fab")
			(hide yes)
			(effects
				(font
					(size 1 1)
					(thickness 0.15)
				)
				(justify mirror)
			)
		)
		(property "License" "Apache-2.0"
			(at 0 0 90)
			(unlocked yes)
			(layer "B.Fab")
			(hide yes)
			(effects
				(font
					(size 1 1)
					(thickness 0.15)
				)
				(justify mirror)
			)
		)
		(property "Author" "Antmicro"
			(at 0 0 90)
			(unlocked yes)
			(layer "B.Fab")
			(hide yes)
			(effects
				(font
					(size 1 1)
					(thickness 0.15)
				)
				(justify mirror)
			)
		)
		(property ki_fp_filters "SOT?323*")
		(sheetname "/TB Controller - Power/")
		(sheetfile "tb-power.kicad_sch")
		(attr smd)
		(fp_line
			(start 0.8 -1.199)
			(end 0.8 -0.9)
			(stroke
				(width 0.15)
				(type solid)
			)
			(layer "B.SilkS")
		)
		(fp_line
			(start 0.498 -1.199)
			(end 0.8 -1.199)
			(stroke
				(width 0.15)
				(type solid)
			)
			(layer "B.SilkS")
		)
		(fp_line
			(start -0.802 -1.199)
			(end -0.5 -1.199)
			(stroke
				(width 0.15)
				(type solid)
			)
			(layer "B.SilkS")
		)
		(fp_line
			(start -0.802 -1.05)
			(end -0.802 -1.199)
			(stroke
				(width 0.15)
				(type solid)
			)
			(layer "B.SilkS")
		)
		(fp_line
			(start 0.8 1.2)
			(end 0.8 0.902)
			(stroke
				(width 0.15)
				(type solid)
			)
			(layer "B.SilkS")
		)
		(fp_line
			(start 0.498 1.2)
			(end 0.8 1.2)
			(stroke
				(width 0.15)
				(type solid)
			)
			(layer "B.SilkS")
		)
		(fp_line
			(start -0.402 1.2)
			(end -0.802 1.2)
			(stroke
				(width 0.15)
				(type solid)
			)
			(layer "B.SilkS")
		)
		(fp_line
			(start -0.802 1.2)
			(end -0.802 1.05)
			(stroke
				(width 0.15)
				(type solid)
			)
			(layer "B.SilkS")
		)
		(fp_circle
			(center -1.05 1.156824)
			(end -1 1.129824)
			(stroke
				(width 0.15)
				(type solid)
			)
			(fill no)
			(layer "B.SilkS")
		)
		(fp_rect
			(start -1.35 1.35)
			(end 1.35 -1.35)
			(stroke
				(width 0.05)
				(type solid)
			)
			(fill no)
			(layer "B.CrtYd")
		)
		(fp_line
			(start -0.677 -1.1)
			(end 0.675 -1.1)
			(stroke
				(width 0.15)
				(type solid)
			)
			(layer "B.Fab")
		)
		(fp_line
			(start 0.675 1.101)
			(end 0.675 -1.1)
			(stroke
				(width 0.15)
				(type solid)
			)
			(layer "B.Fab")
		)
		(fp_line
			(start -0.677 1.101)
			(end -0.677 -1.1)
			(stroke
				(width 0.15)
				(type solid)
			)
			(layer "B.Fab")
		)
		(fp_line
			(start -0.677 1.101)
			(end 0.675 1.101)
			(stroke
				(width 0.15)
				(type solid)
			)
			(layer "B.Fab")
		)
		(fp_text user "${REFERENCE}"
			(at -1.35 -4.749 270)
			(layer "B.Fab")
			(effects
				(font
					(size 0.7 0.7)
					(thickness 0.15)
				)
				(justify left bottom mirror)
			)
		)
		(fp_text user "License: Apache-2.0"
			(at -1.35 -5.949 270)
			(layer "B.Fab")
			(effects
				(font
					(size 0.7 0.7)
					(thickness 0.15)
				)
				(justify left bottom mirror)
			)
		)
		(fp_text user "Author: Antmicro"
			(at -1.35 -7.149 270)
			(layer "B.Fab")
			(effects
				(font
					(size 0.7 0.7)
					(thickness 0.15)
				)
				(justify left bottom mirror)
			)
		)
		(pad "1" smd rect
			(at -0.927 0.652 90)
			(size 0.55 0.6)
			(layers "B.Cu" "B.Mask" "B.Paste")
			(net 196 "Net-(Q1-B)")
			(pinfunction "B")
			(pintype "input")
		)
		(pad "2" smd rect
			(at -0.927 -0.65 90)
			(size 0.55 0.6)
			(layers "B.Cu" "B.Mask" "B.Paste")
			(net 23 "GND")
			(pinfunction "E")
			(pintype "passive")
		)
		(pad "3" smd rect
			(at 0.925 0 90)
			(size 0.55 0.6)
			(layers "B.Cu" "B.Mask" "B.Paste")
			(net 197 "Net-(Q1-C)")
			(pinfunction "C")
			(pintype "passive")
		)
	)
	(footprint "antmicro-footprints:C_0402_1005Metric"
		(layer "B.Cu")
		(at 166.1 133.25)
		(descr "Capacitor SMD 0402")
		(tags "capacitor SMD 0402")
		(property "Reference" "C295"
			(at 1.4 -0.5 180)
			(layer "B.SilkS")
			(effects
				(font
					(size 0.7 0.7)
					(thickness 0.15)
				)
				(justify left bottom mirror)
			)
		)
		(property "Value" "C_1u_25V_0402"
			(at -1.022927 -2.155213 180)
			(layer "B.Fab")
			(effects
				(font
					(size 0.7 0.7)
					(thickness 0.15)
				)
				(justify left bottom mirror)
			)
		)
		(property "Datasheet" "https://www.murata.com/products/productdetail?partno=GRM155R61E105KE11%23"
			(at 0 0 180)
			(layer "B.Fab")
			(hide yes)
			(effects
				(font
					(size 1.27 1.27)
					(thickness 0.15)
				)
				(justify mirror)
			)
		)
		(property "Description" "SMD Multilayer Ceramic Capacitor, 1 µF, 25 V, 0402 [1005 Metric], ± 10%, X5R, GRM Series"
			(at 0 0 180)
			(layer "B.Fab")
			(hide yes)
			(effects
				(font
					(size 1.27 1.27)
					(thickness 0.15)
				)
				(justify mirror)
			)
		)
		(property "MPN" "GRM155R61E105KE11J"
			(at 0 0 0)
			(unlocked yes)
			(layer "B.Fab")
			(hide yes)
			(effects
				(font
					(size 1 1)
					(thickness 0.15)
				)
				(justify mirror)
			)
		)
		(property "Manufacturer" "Murata"
			(at 0 0 0)
			(unlocked yes)
			(layer "B.Fab")
			(hide yes)
			(effects
				(font
					(size 1 1)
					(thickness 0.15)
				)
				(justify mirror)
			)
		)
		(property "License" "Apache-2.0"
			(at 0 0 0)
			(unlocked yes)
			(layer "B.Fab")
			(hide yes)
			(effects
				(font
					(size 1 1)
					(thickness 0.15)
				)
				(justify mirror)
			)
		)
		(property "Author" "Antmicro"
			(at 0 0 0)
			(unlocked yes)
			(layer "B.Fab")
			(hide yes)
			(effects
				(font
					(size 1 1)
					(thickness 0.15)
				)
				(justify mirror)
			)
		)
		(property "Val" "1u"
			(at 0 0 0)
			(unlocked yes)
			(layer "B.Fab")
			(hide yes)
			(effects
				(font
					(size 1 1)
					(thickness 0.15)
				)
				(justify mirror)
			)
		)
		(property "Voltage" "25V"
			(at 0 0 0)
			(unlocked yes)
			(layer "B.Fab")
			(hide yes)
			(effects
				(font
					(size 1 1)
					(thickness 0.15)
				)
				(justify mirror)
			)
		)
		(property "Dielectric" "X5R"
			(at 0 0 0)
			(unlocked yes)
			(layer "B.Fab")
			(hide yes)
			(effects
				(font
					(size 1 1)
					(thickness 0.15)
				)
				(justify mirror)
			)
		)
		(sheetname "/2xRJ45/")
		(sheetfile "2xrj45.kicad_sch")
		(attr smd)
		(fp_rect
			(start -0.925 0.47)
			(end 0.925 -0.47)
			(stroke
				(width 0.05)
				(type default)
			)
			(fill no)
			(layer "B.CrtYd")
		)
		(fp_line
			(start -0.494 -0.248)
			(end -0.494 0.25)
			(stroke
				(width 0.15)
				(type solid)
			)
			(layer "B.Fab")
		)
		(fp_line
			(start -0.494 0.25)
			(end 0.504 0.25)
			(stroke
				(width 0.15)
				(type solid)
			)
			(layer "B.Fab")
		)
		(fp_line
			(start 0.504 -0.248)
			(end -0.494 -0.248)
			(stroke
				(width 0.15)
				(type solid)
			)
			(layer "B.Fab")
		)
		(fp_line
			(start 0.504 0.25)
			(end 0.504 -0.248)
			(stroke
				(width 0.15)
				(type solid)
			)
			(layer "B.Fab")
		)
		(fp_text user "Author: Antmicro"
			(at -0.939 -3.399 180)
			(layer "B.Fab")
			(effects
				(font
					(size 0.7 0.7)
					(thickness 0.15)
				)
				(justify left bottom mirror)
			)
		)
		(fp_text user "License: Apache-2.0"
			(at -0.939 -5.799 180)
			(layer "B.Fab")
			(effects
				(font
					(size 0.7 0.7)
					(thickness 0.15)
				)
				(justify left bottom mirror)
			)
		)
		(fp_text user "${REFERENCE}"
			(at -0.939 -4.599 180)
			(layer "B.Fab")
			(effects
				(font
					(size 0.7 0.7)
					(thickness 0.15)
				)
				(justify left bottom mirror)
			)
		)
		(pad "1" smd roundrect
			(at -0.48 0)
			(size 0.59 0.64)
			(layers "B.Cu" "B.Mask" "B.Paste")
			(roundrect_rratio 0.25)
			(net 23 "GND")
			(pintype "passive")
		)
		(pad "2" smd roundrect
			(at 0.48 0)
			(size 0.59 0.64)
			(layers "B.Cu" "B.Mask" "B.Paste")
			(roundrect_rratio 0.25)
			(net 134 "/2xRJ45/P1_CT")
			(pintype "passive")
		)
	)
	(footprint "antmicro-footprints:R_0402_1005Metric"
		(layer "B.Cu")
		(at 149.131866 70.035118 90)
		(descr "Resistor SMD 0402")
		(tags "resistor SMD 0402")
		(property "Reference" "R195"
			(at -9.464883 19.468134 270)
			(layer "B.SilkS")
			(effects
				(font
					(size 0.7 0.7)
					(thickness 0.15)
				)
				(justify mirror)
			)
		)
		(property "Value" "R_3k3_0402"
			(at -1.011843 -1.772047 270)
			(layer "B.Fab")
			(effects
				(font
					(size 0.7 0.7)
					(thickness 0.15)
				)
				(justify left bottom mirror)
			)
		)
		(property "Datasheet" "https://www.bourns.com/docs/product-datasheets/cr.pdf"
			(at 0 0 270)
			(layer "B.Fab")
			(hide yes)
			(effects
				(font
					(size 1.27 1.27)
					(thickness 0.15)
				)
				(justify mirror)
			)
		)
		(property "Description" "SMD Chip Resistor, 3.3 kohm, ± 1%, 63 mW, 0402 [1005 Metric], Thick Film, General Purpose"
			(at 0 0 270)
			(layer "B.Fab")
			(hide yes)
			(effects
				(font
					(size 1.27 1.27)
					(thickness 0.15)
				)
				(justify mirror)
			)
		)
		(property "MPN" "CR0402-FX-3301GLF"
			(at 0 0 90)
			(unlocked yes)
			(layer "B.Fab")
			(hide yes)
			(effects
				(font
					(size 1 1)
					(thickness 0.15)
				)
				(justify mirror)
			)
		)
		(property "Manufacturer" "Bourns"
			(at 0 0 90)
			(unlocked yes)
			(layer "B.Fab")
			(hide yes)
			(effects
				(font
					(size 1 1)
					(thickness 0.15)
				)
				(justify mirror)
			)
		)
		(property "License" "Apache-2.0"
			(at 0 0 90)
			(unlocked yes)
			(layer "B.Fab")
			(hide yes)
			(effects
				(font
					(size 1 1)
					(thickness 0.15)
				)
				(justify mirror)
			)
		)
		(property "Author" "Antmicro"
			(at 0 0 90)
			(unlocked yes)
			(layer "B.Fab")
			(hide yes)
			(effects
				(font
					(size 1 1)
					(thickness 0.15)
				)
				(justify mirror)
			)
		)
		(property "Val" "3k3"
			(at 0 0 90)
			(unlocked yes)
			(layer "B.Fab")
			(hide yes)
			(effects
				(font
					(size 1 1)
					(thickness 0.15)
				)
				(justify mirror)
			)
		)
		(property "Tolerance" "1%"
			(at 0 0 90)
			(unlocked yes)
			(layer "B.Fab")
			(hide yes)
			(effects
				(font
					(size 1 1)
					(thickness 0.15)
				)
				(justify mirror)
			)
		)
		(sheetname "/X710-AT2 10GbE/")
		(sheetfile "x710-at2-10gbe.kicad_sch")
		(attr smd)
		(fp_rect
			(start -0.925 0.47)
			(end 0.925 -0.47)
			(stroke
				(width 0.05)
				(type default)
			)
			(fill no)
			(layer "B.CrtYd")
		)
		(fp_rect
			(start -0.5 0.25)
			(end 0.5 -0.25)
			(stroke
				(width 0.15)
				(type solid)
			)
			(fill no)
			(layer "B.Fab")
		)
		(fp_text user "Author: Antmicro"
			(at -0.95 -4.169 270)
			(layer "B.Fab")
			(effects
				(font
					(size 0.7 0.7)
					(thickness 0.15)
				)
				(justify left bottom mirror)
			)
		)
		(fp_text user "License: Apache-2.0"
			(at -0.95 -5.169 270)
			(layer "B.Fab")
			(effects
				(font
					(size 0.7 0.7)
					(thickness 0.15)
				)
				(justify left bottom mirror)
			)
		)
		(fp_text user "${REFERENCE}"
			(at -0.95 -3.168 270)
			(layer "B.Fab")
			(effects
				(font
					(size 0.7 0.7)
					(thickness 0.15)
				)
				(justify left bottom mirror)
			)
		)
		(pad "1" smd roundrect
			(at -0.48 0 90)
			(size 0.59 0.64)
			(layers "B.Cu" "B.Mask" "B.Paste")
			(roundrect_rratio 0.25)
			(net 77 "/X710-AT2 10GbE/MDC1_SCL1")
			(pintype "passive")
		)
		(pad "2" smd roundrect
			(at 0.48 0 90)
			(size 0.59 0.64)
			(layers "B.Cu" "B.Mask" "B.Paste")
			(roundrect_rratio 0.25)
			(net 7 "+3V3")
			(pintype "passive")
		)
	)
	(footprint "antmicro-footprints:R_0402_1005Metric"
		(layer "B.Cu")
		(at 122.75 128.025001 180)
		(descr "Resistor SMD 0402")
		(tags "resistor SMD 0402")
		(property "Reference" "R61"
			(at 2.25 0 0)
			(layer "B.SilkS")
			(effects
				(font
					(size 0.7 0.7)
					(thickness 0.15)
				)
				(justify mirror)
			)
		)
		(property "Value" "R_499R_0402"
			(at -1.011843 -1.772047 0)
			(layer "B.Fab")
			(effects
				(font
					(size 0.7 0.7)
					(thickness 0.15)
				)
				(justify left bottom mirror)
			)
		)
		(property "Datasheet" "https://www.mouser.com/datasheet/2/54/cr-1858361.pdf"
			(at 0 0 0)
			(layer "B.Fab")
			(hide yes)
			(effects
				(font
					(size 1.27 1.27)
					(thickness 0.15)
				)
				(justify mirror)
			)
		)
		(property "Description" "SMD Chip Resistor, 499 ohm, ± 1%, 63 mW, 0402 [1005 Metric], Thick Film, General Purpose"
			(at 0 0 0)
			(layer "B.Fab")
			(hide yes)
			(effects
				(font
					(size 1.27 1.27)
					(thickness 0.15)
				)
				(justify mirror)
			)
		)
		(property "MPN" "CR0402-FX-4990GLF"
			(at 0 0 180)
			(unlocked yes)
			(layer "B.Fab")
			(hide yes)
			(effects
				(font
					(size 1 1)
					(thickness 0.15)
				)
				(justify mirror)
			)
		)
		(property "Manufacturer" "Bourns"
			(at 0 0 180)
			(unlocked yes)
			(layer "B.Fab")
			(hide yes)
			(effects
				(font
					(size 1 1)
					(thickness 0.15)
				)
				(justify mirror)
			)
		)
		(property "License" "Apache-2.0"
			(at 0 0 180)
			(unlocked yes)
			(layer "B.Fab")
			(hide yes)
			(effects
				(font
					(size 1 1)
					(thickness 0.15)
				)
				(justify mirror)
			)
		)
		(property "Val" "499R"
			(at 0 0 180)
			(unlocked yes)
			(layer "B.Fab")
			(hide yes)
			(effects
				(font
					(size 1 1)
					(thickness 0.15)
				)
				(justify mirror)
			)
		)
		(property "Tolerance" "1%"
			(at 0 0 180)
			(unlocked yes)
			(layer "B.Fab")
			(hide yes)
			(effects
				(font
					(size 1 1)
					(thickness 0.15)
				)
				(justify mirror)
			)
		)
		(property "Author" "Antmicro"
			(at 0 0 180)
			(unlocked yes)
			(layer "B.Fab")
			(hide yes)
			(effects
				(font
					(size 1 1)
					(thickness 0.15)
				)
				(justify mirror)
			)
		)
		(sheetname "/TB Controller/")
		(sheetfile "tb.kicad_sch")
		(attr smd)
		(fp_rect
			(start -0.925 0.47)
			(end 0.925 -0.47)
			(stroke
				(width 0.05)
				(type default)
			)
			(fill no)
			(layer "B.CrtYd")
		)
		(fp_rect
			(start -0.5 0.25)
			(end 0.5 -0.25)
			(stroke
				(width 0.15)
				(type solid)
			)
			(fill no)
			(layer "B.Fab")
		)
		(fp_text user "${REFERENCE}"
			(at -0.95 -3.168 0)
			(layer "B.Fab")
			(effects
				(font
					(size 0.7 0.7)
					(thickness 0.15)
				)
				(justify left bottom mirror)
			)
		)
		(fp_text user "License: Apache-2.0"
			(at -0.95 -5.169 0)
			(layer "B.Fab")
			(effects
				(font
					(size 0.7 0.7)
					(thickness 0.15)
				)
				(justify left bottom mirror)
			)
		)
		(fp_text user "Author: Antmicro"
			(at -0.95 -4.169 0)
			(layer "B.Fab")
			(effects
				(font
					(size 0.7 0.7)
					(thickness 0.15)
				)
				(justify left bottom mirror)
			)
		)
		(pad "1" smd roundrect
			(at -0.48 0 180)
			(size 0.59 0.64)
			(layers "B.Cu" "B.Mask" "B.Paste")
			(roundrect_rratio 0.25)
			(net 234 "Net-(U4E-PB_USB2_RBIAS)")
			(pintype "passive")
		)
		(pad "2" smd roundrect
			(at 0.48 0 180)
			(size 0.59 0.64)
			(layers "B.Cu" "B.Mask" "B.Paste")
			(roundrect_rratio 0.25)
			(net 23 "GND")
			(pintype "passive")
		)
	)
)
